(kicad_pcb
	(version 20260206)
	(generator "pcbnew")
	(generator_version "10.0")
	(general
		(thickness 1.6)
		(legacy_teardrops no)
	)
	(paper "A4")
	(title_block
		(title "baseboard — 13948-1b.1110WZS1818.brd")
		(comment 1 "Honey Badger (Wiwynn) / footprint 1028 of 2523 (U40), pads 112-225 of 408")
	)
	(layers
		(0 "F.Cu" signal "TOP")
		(4 "In1.Cu" signal "L2GND")
		(6 "In2.Cu" signal "L3")
		(8 "In3.Cu" signal "L4VCC")
		(10 "In4.Cu" signal "L5VCC")
		(12 "In5.Cu" signal "L6")
		(14 "In6.Cu" signal "L7GND")
		(2 "B.Cu" signal "BOTTOM")
		(9 "F.Adhes" user "F.Adhesive")
		(11 "B.Adhes" user "B.Adhesive")
		(13 "F.Paste" user "Package Geometry/Pastemask Top")
		(15 "B.Paste" user "Package Geometry/Pastemask Bottom")
		(5 "F.SilkS" user "Ref Des/Silkscreen Top")
		(7 "B.SilkS" user "Ref Des/Silkscreen Bottom")
		(1 "F.Mask" user "Board Geometry/Soldermask Top")
		(3 "B.Mask" user "Board Geometry/Soldermask Bottom")
		(17 "Dwgs.User" user "User.Drawings")
		(19 "Cmts.User" user "User.Comments")
		(21 "Eco1.User" user "User.Eco1")
		(23 "Eco2.User" user "User.Eco2")
		(25 "Edge.Cuts" user "Board Geometry/Outline")
		(27 "Margin" user)
		(31 "F.CrtYd" user "Package Geometry/Place Bound Top")
		(29 "B.CrtYd" user "Package Geometry/Place Bound Bottom")
		(35 "F.Fab" user "Ref Des/Assembly Top")
		(33 "B.Fab" user "Ref Des/Assembly Bottom")
	)
	(footprint ""
		(layer "F.Cu")
		(at 293.234872 -175.840136 180)
		(property "Reference" "U40"
			(at 0 0 180)
			(layer "F.SilkS")
			(hide yes)
			(effects
				(font
					(size 1.27 1.27)
				)
			)
		)
		(property "Value" "AST1250A1-GP"
			(at -17.7292 -6.184392 180)
			(unlocked yes)
			(layer "F.Fab")
			(hide yes)
			(effects
				(font
					(size 1.016 1.016)
					(thickness 0.1524)
				)
			)
		)
		(property "Device Type" "BGA408D19H52"
			(at -17.7292 -7.708392 180)
			(unlocked yes)
			(layer "F.Fab")
			(hide yes)
			(effects
				(font
					(size 1.016 1.016)
					(thickness 0.1524)
				)
			)
		)
		(duplicate_pad_numbers_are_jumpers no)
		(pad "D2" smd circle
			(at -7.599934 -5.999988 180)
			(size 0.3556 0.3556)
			(layers "F.Cu" "F.Mask" "F.Paste")
			(net "BMC0_SMB5_DAT")
		)
		(pad "D3" smd circle
			(at -6.800088 -5.999988 180)
			(size 0.3556 0.3556)
			(layers "F.Cu" "F.Mask" "F.Paste")
			(net "BMC0_SMB3_CLK")
		)
		(pad "D4" smd circle
			(at -5.999988 -5.999988 180)
			(size 0.3556 0.3556)
			(layers "F.Cu" "F.Mask" "F.Paste")
			(net "PU_BMC0_SCL12")
		)
		(pad "D5" smd circle
			(at -5.199888 -5.999988 180)
			(size 0.3556 0.3556)
			(layers "F.Cu" "F.Mask" "F.Paste")
			(net "TP_BMC_GPIOA7")
		)
		(pad "D6" smd circle
			(at -4.400042 -5.999988 180)
			(size 0.3556 0.3556)
			(layers "F.Cu" "F.Mask" "F.Paste")
			(net "PEER_TRAY_BMC")
		)
		(pad "D7" smd circle
			(at -3.599942 -5.999988 180)
			(size 0.3556 0.3556)
			(layers "F.Cu" "F.Mask" "F.Paste")
			(net "TP_GPIOH4")
		)
		(pad "D8" smd circle
			(at -2.800096 -5.999988 180)
			(size 0.3556 0.3556)
			(layers "F.Cu" "F.Mask" "F.Paste")
			(net "NCSI_10G_RCSDV")
		)
		(pad "D9" smd circle
			(at -1.999996 -5.999988 180)
			(size 0.3556 0.3556)
			(layers "F.Cu" "F.Mask" "F.Paste")
			(net "NCSI_10G_TXEN")
		)
		(pad "D10" smd circle
			(at -1.199896 -5.999988 180)
			(size 0.3556 0.3556)
			(layers "F.Cu" "F.Mask" "F.Paste")
			(net "TP_BMC_GPIOU3")
		)
		(pad "D11" smd circle
			(at -0.40005 -5.999988 180)
			(size 0.3556 0.3556)
			(layers "F.Cu" "F.Mask" "F.Paste")
			(net "GND")
		)
		(pad "D12" smd circle
			(at 0.40005 -5.999988 180)
			(size 0.3556 0.3556)
			(layers "F.Cu" "F.Mask" "F.Paste")
			(net "RMII0_BMC_C_PHY_TXD1")
		)
		(pad "D13" smd circle
			(at 1.199896 -5.999988 180)
			(size 0.3556 0.3556)
			(layers "F.Cu" "F.Mask" "F.Paste")
			(net "HIGH_HEX_2")
		)
		(pad "D14" smd circle
			(at 1.999996 -5.999988 180)
			(size 0.3556 0.3556)
			(layers "F.Cu" "F.Mask" "F.Paste")
			(net "TP_BMC_GPIOE5")
		)
		(pad "D15" smd circle
			(at 2.800096 -5.999988 180)
			(size 0.3556 0.3556)
			(layers "F.Cu" "F.Mask" "F.Paste")
			(net "TP_BMC_GPIOE0")
		)
		(pad "D16" smd circle
			(at 3.599942 -5.999988 180)
			(size 0.3556 0.3556)
			(layers "F.Cu" "F.Mask" "F.Paste")
			(net "BMC_RSTBTN_N_R")
		)
		(pad "D17" smd circle
			(at 4.400042 -5.999988 180)
			(size 0.3556 0.3556)
			(layers "F.Cu" "F.Mask" "F.Paste")
			(net "TP_BMC_GPIOF3")
		)
		(pad "D18" smd circle
			(at 5.199888 -5.999988 180)
			(size 0.3556 0.3556)
			(layers "F.Cu" "F.Mask" "F.Paste")
			(net "TP_BMC_GPIOF0")
		)
		(pad "D19" smd circle
			(at 5.999988 -5.999988 180)
			(size 0.3556 0.3556)
			(layers "F.Cu" "F.Mask" "F.Paste")
			(net "BMC_RST_EXPANDER")
		)
		(pad "D20" smd circle
			(at 6.800088 -5.999988 180)
			(size 0.3556 0.3556)
			(layers "F.Cu" "F.Mask" "F.Paste")
			(net "Net_1409")
		)
		(pad "D21" smd circle
			(at 7.599934 -5.999988 180)
			(size 0.3556 0.3556)
			(layers "F.Cu" "F.Mask" "F.Paste")
			(net "GND")
		)
		(pad "D22" smd circle
			(at 8.400034 -5.999988 180)
			(size 0.3556 0.3556)
			(layers "F.Cu" "F.Mask" "F.Paste")
			(net "GND")
		)
		(pad "E1" smd circle
			(at -8.400034 -5.199888 180)
			(size 0.3556 0.3556)
			(layers "F.Cu" "F.Mask" "F.Paste")
			(net "JTAG_BMC_TRST_N")
		)
		(pad "E2" smd circle
			(at -7.599934 -5.199888 180)
			(size 0.3556 0.3556)
			(layers "F.Cu" "F.Mask" "F.Paste")
			(net "BMC0_SMB7_CLK")
		)
		(pad "E3" smd circle
			(at -6.800088 -5.199888 180)
			(size 0.3556 0.3556)
			(layers "F.Cu" "F.Mask" "F.Paste")
			(net "BMC0_SMB5_CLK")
		)
		(pad "E4" smd circle
			(at -5.999988 -5.199888 180)
			(size 0.3556 0.3556)
			(layers "F.Cu" "F.Mask" "F.Paste")
			(net "BMC0_ENTEST1")
		)
		(pad "E5" smd circle
			(at -5.199888 -5.199888 180)
			(size 0.3556 0.3556)
			(layers "F.Cu" "F.Mask" "F.Paste")
			(net "PU_BMC0_SDA11")
		)
		(pad "E6" smd circle
			(at -4.400042 -5.199888 180)
			(size 0.3556 0.3556)
			(layers "F.Cu" "F.Mask" "F.Paste")
			(net "EXP_ID_BMC")
		)
		(pad "E7" smd circle
			(at -3.599942 -5.199888 180)
			(size 0.3556 0.3556)
			(layers "F.Cu" "F.Mask" "F.Paste")
			(net "TP_GPIOH7")
		)
		(pad "E8" smd circle
			(at -2.800096 -5.199888 180)
			(size 0.3556 0.3556)
			(layers "F.Cu" "F.Mask" "F.Paste")
			(net "NCSI_10G_RXD1")
		)
		(pad "E9" smd circle
			(at -1.999996 -5.199888 180)
			(size 0.3556 0.3556)
			(layers "F.Cu" "F.Mask" "F.Paste")
			(net "TP_BMC_GPIOT7")
		)
		(pad "E10" smd circle
			(at -1.199896 -5.199888 180)
			(size 0.3556 0.3556)
			(layers "F.Cu" "F.Mask" "F.Paste")
			(net "RMII0_BMC_C_RX_ER")
		)
		(pad "E11" smd circle
			(at -0.40005 -5.199888 180)
			(size 0.3556 0.3556)
			(layers "F.Cu" "F.Mask" "F.Paste")
			(net "BMC_RXCK_R")
		)
		(pad "E12" smd circle
			(at 0.40005 -5.199888 180)
			(size 0.3556 0.3556)
			(layers "F.Cu" "F.Mask" "F.Paste")
			(net "GND")
		)
		(pad "E13" smd circle
			(at 1.199896 -5.199888 180)
			(size 0.3556 0.3556)
			(layers "F.Cu" "F.Mask" "F.Paste")
			(net "HIGH_HEX_1")
		)
		(pad "E14" smd circle
			(at 1.999996 -5.199888 180)
			(size 0.3556 0.3556)
			(layers "F.Cu" "F.Mask" "F.Paste")
			(net "TP_BMC_GPIOE4")
		)
		(pad "E15" smd circle
			(at 2.800096 -5.199888 180)
			(size 0.3556 0.3556)
			(layers "F.Cu" "F.Mask" "F.Paste")
			(net "BMC0_TP15")
		)
		(pad "E16" smd circle
			(at 3.599942 -5.199888 180)
			(size 0.3556 0.3556)
			(layers "F.Cu" "F.Mask" "F.Paste")
			(net "TP_BMC_GPIOF6")
		)
		(pad "E17" smd circle
			(at 4.400042 -5.199888 180)
			(size 0.3556 0.3556)
			(layers "F.Cu" "F.Mask" "F.Paste")
			(net "TP_IRQ_CPU_SERIAL")
		)
		(pad "E18" smd circle
			(at 5.199888 -5.199888 180)
			(size 0.3556 0.3556)
			(layers "F.Cu" "F.Mask" "F.Paste")
			(net "TP_BMC_GPIOB7")
		)
		(pad "E19" smd circle
			(at 5.999988 -5.199888 180)
			(size 0.3556 0.3556)
			(layers "F.Cu" "F.Mask" "F.Paste")
			(net "LPCRST0_N")
		)
		(pad "E20" smd circle
			(at 6.800088 -5.199888 180)
			(size 0.3556 0.3556)
			(layers "F.Cu" "F.Mask" "F.Paste")
			(net "PWGD_P0V955_C_PG_R")
		)
		(pad "E21" smd circle
			(at 7.599934 -5.199888 180)
			(size 0.3556 0.3556)
			(layers "F.Cu" "F.Mask" "F.Paste")
			(net "Net_1408")
		)
		(pad "E22" smd circle
			(at 8.400034 -5.199888 180)
			(size 0.3556 0.3556)
			(layers "F.Cu" "F.Mask" "F.Paste")
			(net "Net_1407")
		)
		(pad "F1" smd circle
			(at -8.400034 -4.400042 180)
			(size 0.3556 0.3556)
			(layers "F.Cu" "F.Mask" "F.Paste")
			(net "JTAG_BMC_TDI")
		)
		(pad "F2" smd circle
			(at -7.599934 -4.400042 180)
			(size 0.3556 0.3556)
			(layers "F.Cu" "F.Mask" "F.Paste")
			(net "JTAG_BMC_TCK")
		)
		(pad "F3" smd circle
			(at -6.800088 -4.400042 180)
			(size 0.3556 0.3556)
			(layers "F.Cu" "F.Mask" "F.Paste")
			(net "BMC0_SMB8_DAT")
		)
		(pad "F4" smd circle
			(at -5.999988 -4.400042 180)
			(size 0.3556 0.3556)
			(layers "F.Cu" "F.Mask" "F.Paste")
			(net "BMC0_SMB6_DAT")
		)
		(pad "F5" smd circle
			(at -5.199888 -4.400042 180)
			(size 0.3556 0.3556)
			(layers "F.Cu" "F.Mask" "F.Paste")
			(net "BMC0_SMB4_DAT")
		)
		(pad "F8" smd circle
			(at -2.800096 -4.400042 180)
			(size 0.3556 0.3556)
			(layers "F.Cu" "F.Mask" "F.Paste")
			(net "P3V3_STBY")
		)
		(pad "F9" smd circle
			(at -1.999996 -4.400042 180)
			(size 0.3556 0.3556)
			(layers "F.Cu" "F.Mask" "F.Paste")
			(net "P3V3_STBY")
		)
		(pad "F10" smd circle
			(at -1.199896 -4.400042 180)
			(size 0.3556 0.3556)
			(layers "F.Cu" "F.Mask" "F.Paste")
			(net "P3V3_STBY")
		)
		(pad "F11" smd circle
			(at -0.40005 -4.400042 180)
			(size 0.3556 0.3556)
			(layers "F.Cu" "F.Mask" "F.Paste")
			(net "P3V3_STBY")
		)
		(pad "F12" smd circle
			(at 0.40005 -4.400042 180)
			(size 0.3556 0.3556)
			(layers "F.Cu" "F.Mask" "F.Paste")
			(net "P3V3_STBY")
		)
		(pad "F13" smd circle
			(at 1.199896 -4.400042 180)
			(size 0.3556 0.3556)
			(layers "F.Cu" "F.Mask" "F.Paste")
			(net "P3V3_STBY")
		)
		(pad "F14" smd circle
			(at 1.999996 -4.400042 180)
			(size 0.3556 0.3556)
			(layers "F.Cu" "F.Mask" "F.Paste")
			(net "P1V26_STBY")
		)
		(pad "F15" smd circle
			(at 2.800096 -4.400042 180)
			(size 0.3556 0.3556)
			(layers "F.Cu" "F.Mask" "F.Paste")
			(net "P1V26_STBY")
		)
		(pad "F18" smd circle
			(at 5.199888 -4.400042 180)
			(size 0.3556 0.3556)
			(layers "F.Cu" "F.Mask" "F.Paste")
			(net "BMC_SALT4")
		)
		(pad "F19" smd circle
			(at 5.999988 -4.400042 180)
			(size 0.3556 0.3556)
			(layers "F.Cu" "F.Mask" "F.Paste")
			(net "TP_BMC0_LPC_LAD2")
		)
		(pad "F20" smd circle
			(at 6.800088 -4.400042 180)
			(size 0.3556 0.3556)
			(layers "F.Cu" "F.Mask" "F.Paste")
			(net "FCB_HW_REVISION")
		)
		(pad "F21" smd circle
			(at 7.599934 -4.400042 180)
			(size 0.3556 0.3556)
			(layers "F.Cu" "F.Mask" "F.Paste")
			(net "GND")
		)
		(pad "F22" smd circle
			(at 8.400034 -4.400042 180)
			(size 0.3556 0.3556)
			(layers "F.Cu" "F.Mask" "F.Paste")
			(net "GND")
		)
		(pad "G1" smd circle
			(at -8.400034 -3.599942 180)
			(size 0.3556 0.3556)
			(layers "F.Cu" "F.Mask" "F.Paste")
			(net "BMC_RXD5_R")
		)
		(pad "G2" smd circle
			(at -7.599934 -3.599942 180)
			(size 0.3556 0.3556)
			(layers "F.Cu" "F.Mask" "F.Paste")
			(net "JTAG_BMC_TMS")
		)
		(pad "G3" smd circle
			(at -6.800088 -3.599942 180)
			(size 0.3556 0.3556)
			(layers "F.Cu" "F.Mask" "F.Paste")
			(net "JTAG_BMC_TDO")
		)
		(pad "G4" smd circle
			(at -5.999988 -3.599942 180)
			(size 0.3556 0.3556)
			(layers "F.Cu" "F.Mask" "F.Paste")
			(net "BMC0_JTAG_RTCK")
		)
		(pad "G5" smd circle
			(at -5.199888 -3.599942 180)
			(size 0.3556 0.3556)
			(layers "F.Cu" "F.Mask" "F.Paste")
			(net "BMC0_SMB8_CLK")
		)
		(pad "G18" smd circle
			(at 5.199888 -3.599942 180)
			(size 0.3556 0.3556)
			(layers "F.Cu" "F.Mask" "F.Paste")
			(net "PMU_WAKE_N")
		)
		(pad "G19" smd circle
			(at 5.999988 -3.599942 180)
			(size 0.3556 0.3556)
			(layers "F.Cu" "F.Mask" "F.Paste")
			(net "BMC_1V8_C_EN_R")
		)
		(pad "G20" smd circle
			(at 6.800088 -3.599942 180)
			(size 0.3556 0.3556)
			(layers "F.Cu" "F.Mask" "F.Paste")
			(net "DPB_HW_REVISION")
		)
		(pad "G21" smd circle
			(at 7.599934 -3.599942 180)
			(size 0.3556 0.3556)
			(layers "F.Cu" "F.Mask" "F.Paste")
			(net "GND")
		)
		(pad "G22" smd circle
			(at 8.400034 -3.599942 180)
			(size 0.3556 0.3556)
			(layers "F.Cu" "F.Mask" "F.Paste")
			(net "GND")
		)
		(pad "H1" smd circle
			(at -8.400034 -2.800096 180)
			(size 0.3556 0.3556)
			(layers "F.Cu" "F.Mask" "F.Paste")
			(net "BMC_JTAG_L_R")
		)
		(pad "H2" smd circle
			(at -7.599934 -2.800096 180)
			(size 0.3556 0.3556)
			(layers "F.Cu" "F.Mask" "F.Paste")
			(net "TP_BMC_GPIOQ6")
		)
		(pad "H3" smd circle
			(at -6.800088 -2.800096 180)
			(size 0.3556 0.3556)
			(layers "F.Cu" "F.Mask" "F.Paste")
			(net "BMC0_SMB14_SDA")
		)
		(pad "H4" smd circle
			(at -5.999988 -2.800096 180)
			(size 0.3556 0.3556)
			(layers "F.Cu" "F.Mask" "F.Paste")
			(net "BMC0_SMB14_CLK")
		)
		(pad "H5" smd circle
			(at -5.199888 -2.800096 180)
			(size 0.3556 0.3556)
			(layers "F.Cu" "F.Mask" "F.Paste")
			(net "BMC_TXD5_R")
		)
		(pad "H6" smd circle
			(at -4.400042 -2.800096 180)
			(size 0.3556 0.3556)
			(layers "F.Cu" "F.Mask" "F.Paste")
			(net "P3V3_STBY")
		)
		(pad "H17" smd circle
			(at 4.400042 -2.800096 180)
			(size 0.3556 0.3556)
			(layers "F.Cu" "F.Mask" "F.Paste")
			(net "P3V3_STBY")
		)
		(pad "H18" smd circle
			(at 5.199888 -2.800096 180)
			(size 0.3556 0.3556)
			(layers "F.Cu" "F.Mask" "F.Paste")
			(net "BMC_SALT3")
		)
		(pad "H19" smd circle
			(at 5.999988 -2.800096 180)
			(size 0.3556 0.3556)
			(layers "F.Cu" "F.Mask" "F.Paste")
			(net "DEBUG_LED_SW")
		)
		(pad "H20" smd circle
			(at 6.800088 -2.800096 180)
			(size 0.3556 0.3556)
			(layers "F.Cu" "F.Mask" "F.Paste")
			(net "HSC_MSB_ALERT_N")
		)
		(pad "H21" smd circle
			(at 7.599934 -2.800096 180)
			(size 0.3556 0.3556)
			(layers "F.Cu" "F.Mask" "F.Paste")
			(net "Net_1406")
		)
		(pad "H22" smd circle
			(at 8.400034 -2.800096 180)
			(size 0.3556 0.3556)
			(layers "F.Cu" "F.Mask" "F.Paste")
			(net "Net_1405")
		)
		(pad "J1" smd circle
			(at -8.400034 -1.999996 180)
			(size 0.3556 0.3556)
			(layers "F.Cu" "F.Mask" "F.Paste")
			(net "BMC_USB1_HDP")
		)
		(pad "J2" smd circle
			(at -7.599934 -1.999996 180)
			(size 0.3556 0.3556)
			(layers "F.Cu" "F.Mask" "F.Paste")
			(net "BMC_USB1_HDN")
		)
		(pad "J3" smd circle
			(at -6.800088 -1.999996 180)
			(size 0.3556 0.3556)
			(layers "F.Cu" "F.Mask" "F.Paste")
			(net "LOW_HEX_3")
		)
		(pad "J4" smd circle
			(at -5.999988 -1.999996 180)
			(size 0.3556 0.3556)
			(layers "F.Cu" "F.Mask" "F.Paste")
			(net "LOW_HEX_1")
		)
		(pad "J5" smd circle
			(at -5.199888 -1.999996 180)
			(size 0.3556 0.3556)
			(layers "F.Cu" "F.Mask" "F.Paste")
			(net "LOW_HEX_0")
		)
		(pad "J6" smd circle
			(at -4.400042 -1.999996 180)
			(size 0.3556 0.3556)
			(layers "F.Cu" "F.Mask" "F.Paste")
			(net "P3V3_STBY")
		)
		(pad "J9" smd circle
			(at -1.999996 -1.999996 180)
			(size 0.3556 0.3556)
			(layers "F.Cu" "F.Mask" "F.Paste")
			(net "GND")
		)
		(pad "J10" smd circle
			(at -1.199896 -1.999996 180)
			(size 0.3556 0.3556)
			(layers "F.Cu" "F.Mask" "F.Paste")
			(net "GND")
		)
		(pad "J11" smd circle
			(at -0.40005 -1.999996 180)
			(size 0.3556 0.3556)
			(layers "F.Cu" "F.Mask" "F.Paste")
			(net "GND")
		)
		(pad "J12" smd circle
			(at 0.40005 -1.999996 180)
			(size 0.3556 0.3556)
			(layers "F.Cu" "F.Mask" "F.Paste")
			(net "GND")
		)
		(pad "J13" smd circle
			(at 1.199896 -1.999996 180)
			(size 0.3556 0.3556)
			(layers "F.Cu" "F.Mask" "F.Paste")
			(net "GND")
		)
		(pad "J14" smd circle
			(at 1.999996 -1.999996 180)
			(size 0.3556 0.3556)
			(layers "F.Cu" "F.Mask" "F.Paste")
			(net "GND")
		)
		(pad "J17" smd circle
			(at 4.400042 -1.999996 180)
			(size 0.3556 0.3556)
			(layers "F.Cu" "F.Mask" "F.Paste")
			(net "P3V3_STBY")
		)
		(pad "J18" smd circle
			(at 5.199888 -1.999996 180)
			(size 0.3556 0.3556)
			(layers "F.Cu" "F.Mask" "F.Paste")
			(net "BMC0_SMB2_DAT")
		)
		(pad "J19" smd circle
			(at 5.999988 -1.999996 180)
			(size 0.3556 0.3556)
			(layers "F.Cu" "F.Mask" "F.Paste")
			(net "BMC0_SMB2_CLK")
		)
		(pad "J20" smd circle
			(at 6.800088 -1.999996 180)
			(size 0.3556 0.3556)
			(layers "F.Cu" "F.Mask" "F.Paste")
			(net "I2C_BMC_10G_ALERT#")
		)
		(pad "J21" smd circle
			(at 7.599934 -1.999996 180)
			(size 0.3556 0.3556)
			(layers "F.Cu" "F.Mask" "F.Paste")
			(net "BMC_MSB_I2C_E_ALERT_#")
		)
		(pad "J22" smd circle
			(at 8.400034 -1.999996 180)
			(size 0.3556 0.3556)
			(layers "F.Cu" "F.Mask" "F.Paste")
			(net "GND")
		)
		(pad "K1" smd circle
			(at -8.400034 -1.199896 180)
			(size 0.3556 0.3556)
			(layers "F.Cu" "F.Mask" "F.Paste")
			(net "ADCVREFFP")
		)
		(pad "K2" smd circle
			(at -7.599934 -1.199896 180)
			(size 0.3556 0.3556)
			(layers "F.Cu" "F.Mask" "F.Paste")
			(net "ADCVREFFN")
		)
		(pad "K3" smd circle
			(at -6.800088 -1.199896 180)
			(size 0.3556 0.3556)
			(layers "F.Cu" "F.Mask" "F.Paste")
			(net "BMC_USB1_HDN2")
		)
		(pad "K4" smd circle
			(at -5.999988 -1.199896 180)
			(size 0.3556 0.3556)
			(layers "F.Cu" "F.Mask" "F.Paste")
			(net "BMC_USB1_HDP2")
		)
		(pad "K5" smd circle
			(at -5.199888 -1.199896 180)
			(size 0.3556 0.3556)
			(layers "F.Cu" "F.Mask" "F.Paste")
			(net "LOW_HEX_2")
		)
		(pad "K6" smd circle
			(at -4.400042 -1.199896 180)
			(size 0.3556 0.3556)
			(layers "F.Cu" "F.Mask" "F.Paste")
			(net "P1V26_STBY")
		)
		(pad "K9" smd circle
			(at -1.999996 -1.199896 180)
			(size 0.3556 0.3556)
			(layers "F.Cu" "F.Mask" "F.Paste")
			(net "GND")
		)
		(pad "K10" smd circle
			(at -1.199896 -1.199896 180)
			(size 0.3556 0.3556)
			(layers "F.Cu" "F.Mask" "F.Paste")
			(net "GND")
		)
		(pad "K11" smd circle
			(at -0.40005 -1.199896 180)
			(size 0.3556 0.3556)
			(layers "F.Cu" "F.Mask" "F.Paste")
			(net "GND")
		)
		(pad "K12" smd circle
			(at 0.40005 -1.199896 180)
			(size 0.3556 0.3556)
			(layers "F.Cu" "F.Mask" "F.Paste")
			(net "GND")
		)
		(pad "K13" smd circle
			(at 1.199896 -1.199896 180)
			(size 0.3556 0.3556)
			(layers "F.Cu" "F.Mask" "F.Paste")
			(net "GND")
		)
		(pad "K14" smd circle
			(at 1.999996 -1.199896 180)
			(size 0.3556 0.3556)
			(layers "F.Cu" "F.Mask" "F.Paste")
			(net "GND")
		)
		(pad "K17" smd circle
			(at 4.400042 -1.199896 180)
			(size 0.3556 0.3556)
			(layers "F.Cu" "F.Mask" "F.Paste")
			(net "P1V26_STBY")
		)
	)
)
